(kicad_pcb
	(version 20260206)
	(generator "pcbnew")
	(generator_version "10.0")
	(general
		(thickness 1.6)
		(legacy_teardrops no)
	)
	(paper "A4")
	(title_block
		(title "01162023_DA0F0TEBIF0_F0T_Expander_BD_F_brd_V02_OCP.brd")
		(comment 1 "Grand Teton / footprints 3841-3847 of 9728")
	)
	(layers
		(0 "F.Cu" signal "TOP")
		(4 "In1.Cu" signal "GND")
		(6 "In2.Cu" signal "VCC")
		(8 "In3.Cu" signal "VCC1")
		(10 "In4.Cu" signal "GND1")
		(12 "In5.Cu" signal "IN1")
		(14 "In6.Cu" signal "GND2")
		(16 "In7.Cu" signal "IN2")
		(18 "In8.Cu" signal "GND3")
		(20 "In9.Cu" signal "IN3")
		(22 "In10.Cu" signal "GND4")
		(24 "In11.Cu" signal "IN4")
		(26 "In12.Cu" signal "GND5")
		(28 "In13.Cu" signal "IN5")
		(30 "In14.Cu" signal "GND6")
		(32 "In15.Cu" signal "IN6")
		(34 "In16.Cu" signal "GND7")
		(2 "B.Cu" signal "BOTTOM")
		(9 "F.Adhes" user "F.Adhesive")
		(11 "B.Adhes" user "B.Adhesive")
		(13 "F.Paste" user "Package Geometry/Pastemask Top")
		(15 "B.Paste" user "Package Geometry/Pastemask Bottom")
		(5 "F.SilkS" user "Ref Des/Silkscreen Top")
		(7 "B.SilkS" user "Ref Des/Silkscreen Bottom")
		(1 "F.Mask" user "Board Geometry/Soldermask Top")
		(3 "B.Mask" user "Board Geometry/Soldermask Bottom")
		(17 "Dwgs.User" user "User.Drawings")
		(19 "Cmts.User" user "User.Comments")
		(21 "Eco1.User" user "User.Eco1")
		(23 "Eco2.User" user "User.Eco2")
		(25 "Edge.Cuts" user "Board Geometry/Outline")
		(27 "Margin" user)
		(31 "F.CrtYd" user "Package Geometry/Place Bound Top")
		(29 "B.CrtYd" user "Package Geometry/Place Bound Bottom")
		(35 "F.Fab" user "Ref Des/Assembly Top")
		(33 "B.Fab" user "Ref Des/Assembly Bottom")
	)
	(footprint ""
		(layer "F.Cu")
		(at 21.176996 -124.008134 90)
		(property "Reference" "PD52"
			(at -2.850134 2.243074 90)
			(unlocked yes)
			(layer "F.SilkS")
			(effects
				(font
					(size 0.7874 0.5842)
					(thickness 0.1524)
				)
				(justify left)
			)
		)
		(property "Value" ""
			(at 0 0 90)
			(layer "F.Fab")
			(effects
				(font
					(size 1.27 1.27)
				)
			)
		)
		(duplicate_pad_numbers_are_jumpers no)
		(fp_line
			(start 4.107942 -1.459992)
			(end 4.107942 1.459992)
			(stroke
				(width 0.1524)
				(type default)
			)
			(layer "F.SilkS")
		)
		(fp_line
			(start -3.400044 -1.459992)
			(end 4.107942 -1.459992)
			(stroke
				(width 0.1524)
				(type default)
			)
			(layer "F.SilkS")
		)
		(fp_line
			(start 4.107942 1.459992)
			(end -3.400044 1.459992)
			(stroke
				(width 0.1524)
				(type default)
			)
			(layer "F.SilkS")
		)
		(fp_line
			(start -3.400044 1.459992)
			(end -3.400044 -1.459992)
			(stroke
				(width 0.1524)
				(type default)
			)
			(layer "F.SilkS")
		)
		(fp_poly
			(pts
				(xy 4.107942 -1.459992) (xy 4.107942 1.459992) (xy 3.308096 1.459992) (xy 3.308096 -1.459992)
			)
			(stroke
				(width 0)
				(type default)
			)
			(fill yes)
			(layer "F.SilkS")
		)
		(fp_line
			(start 2.29997 -1.459992)
			(end 2.29997 1.459992)
			(stroke
				(width 0.1)
				(type default)
			)
			(layer "F.Fab")
		)
		(fp_line
			(start -2.29997 -1.459992)
			(end 2.29997 -1.459992)
			(stroke
				(width 0.1)
				(type default)
			)
			(layer "F.Fab")
		)
		(fp_line
			(start 2.29997 1.459992)
			(end -2.29997 1.459992)
			(stroke
				(width 0.1)
				(type default)
			)
			(layer "F.Fab")
		)
		(fp_line
			(start -2.29997 1.459992)
			(end -2.29997 -1.459992)
			(stroke
				(width 0.1)
				(type default)
			)
			(layer "F.Fab")
		)
		(fp_text user "+"
			(at -4.7752 -0.12065 90)
			(unlocked yes)
			(layer "F.SilkS")
			(effects
				(font
					(size 1.905 1.4224)
					(thickness 0.1524)
				)
				(justify left)
			)
		)
		(fp_text user "-"
			(at 5.4102 0.29845 270)
			(unlocked yes)
			(layer "F.SilkS")
			(effects
				(font
					(size 1.905 1.4224)
					(thickness 0.1524)
				)
				(justify left)
			)
		)
		(fp_text user "+"
			(at -4.7752 -0.12065 90)
			(unlocked yes)
			(layer "F.Fab")
			(effects
				(font
					(size 1.905 1.4224)
					(thickness 0.1524)
				)
				(justify left)
			)
		)
		(fp_text user "-"
			(at 5.4102 0.29845 270)
			(unlocked yes)
			(layer "F.Fab")
			(effects
				(font
					(size 1.905 1.4224)
					(thickness 0.1524)
				)
				(justify left)
			)
		)
		(pad "A" smd rect
			(at -1.999996 0 180)
			(size 1.7018 2.5146)
			(layers "F.Cu" "F.Mask" "F.Paste")
			(net "GND")
		)
		(pad "C" smd rect
			(at 1.999996 0 180)
			(size 1.7018 2.5146)
			(layers "F.Cu" "F.Mask" "F.Paste")
			(net "P3V3_NIC0")
		)
	)
	(footprint ""
		(layer "F.Cu")
		(at 174.219108 -59.574684 90)
		(property "Reference" "PC504"
			(at 0 0 90)
			(layer "F.SilkS")
			(hide yes)
			(effects
				(font
					(size 1.27 1.27)
				)
			)
		)
		(property "Value" ""
			(at 0 0 90)
			(layer "F.Fab")
			(effects
				(font
					(size 1.27 1.27)
				)
			)
		)
		(duplicate_pad_numbers_are_jumpers no)
		(fp_line
			(start 0.7874 -0.4064)
			(end 0.7874 0.4064)
			(stroke
				(width 0.1524)
				(type default)
			)
			(layer "F.SilkS")
		)
		(fp_line
			(start -0.7874 -0.4064)
			(end 0.7874 -0.4064)
			(stroke
				(width 0.1524)
				(type default)
			)
			(layer "F.SilkS")
		)
		(fp_line
			(start 0.7874 0.4064)
			(end -0.7874 0.4064)
			(stroke
				(width 0.1524)
				(type default)
			)
			(layer "F.SilkS")
		)
		(fp_line
			(start -0.7874 0.4064)
			(end -0.7874 -0.4064)
			(stroke
				(width 0.1524)
				(type default)
			)
			(layer "F.SilkS")
		)
		(fp_line
			(start -0.12065 -0.305054)
			(end -0.12065 -0.2794)
			(stroke
				(width 0.1)
				(type default)
			)
			(layer "F.Fab")
		)
		(fp_line
			(start -0.67945 -0.305054)
			(end -0.12065 -0.305054)
			(stroke
				(width 0.1)
				(type default)
			)
			(layer "F.Fab")
		)
		(fp_line
			(start 0.67945 -0.3048)
			(end 0.67945 0.3048)
			(stroke
				(width 0.1)
				(type default)
			)
			(layer "F.Fab")
		)
		(fp_line
			(start 0.12065 -0.3048)
			(end 0.67945 -0.3048)
			(stroke
				(width 0.1)
				(type default)
			)
			(layer "F.Fab")
		)
		(fp_line
			(start 0.12065 -0.2794)
			(end 0.12065 -0.3048)
			(stroke
				(width 0.1)
				(type default)
			)
			(layer "F.Fab")
		)
		(fp_line
			(start -0.12065 -0.2794)
			(end 0.12065 -0.2794)
			(stroke
				(width 0.1)
				(type default)
			)
			(layer "F.Fab")
		)
		(fp_line
			(start 0.120396 0.2794)
			(end -0.12065 0.2794)
			(stroke
				(width 0.1)
				(type default)
			)
			(layer "F.Fab")
		)
		(fp_line
			(start -0.12065 0.2794)
			(end -0.12065 0.3048)
			(stroke
				(width 0.1)
				(type default)
			)
			(layer "F.Fab")
		)
		(fp_line
			(start 0.67945 0.3048)
			(end 0.120396 0.3048)
			(stroke
				(width 0.1)
				(type default)
			)
			(layer "F.Fab")
		)
		(fp_line
			(start 0.120396 0.3048)
			(end 0.120396 0.2794)
			(stroke
				(width 0.1)
				(type default)
			)
			(layer "F.Fab")
		)
		(fp_line
			(start -0.12065 0.3048)
			(end -0.67945 0.3048)
			(stroke
				(width 0.1)
				(type default)
			)
			(layer "F.Fab")
		)
		(fp_line
			(start -0.67945 0.3048)
			(end -0.67945 -0.305054)
			(stroke
				(width 0.1)
				(type default)
			)
			(layer "F.Fab")
		)
		(pad "1" smd circle
			(at -0.40005 0 90)
			(size 0 0)
			(layers "F.Cu" "F.Mask" "F.Paste")
			(net "P5V_AUX")
		)
		(pad "2" smd circle
			(at 0.40005 0 90)
			(size 0 0)
			(layers "F.Cu" "F.Mask" "F.Paste")
			(net "GND")
		)
	)
	(footprint ""
		(layer "F.Cu")
		(at 301.992284 -29.139642 180)
		(property "Reference" "C509"
			(at 0 0 180)
			(layer "F.SilkS")
			(hide yes)
			(effects
				(font
					(size 1.27 1.27)
				)
			)
		)
		(property "Value" ""
			(at 0 0 180)
			(layer "F.Fab")
			(effects
				(font
					(size 1.27 1.27)
				)
			)
		)
		(duplicate_pad_numbers_are_jumpers no)
		(fp_line
			(start 0.299974 0.150114)
			(end -0.299974 0.150114)
			(stroke
				(width 0.1)
				(type default)
			)
			(layer "F.Fab")
		)
		(fp_line
			(start 0.299974 -0.150114)
			(end 0.299974 0.150114)
			(stroke
				(width 0.1)
				(type default)
			)
			(layer "F.Fab")
		)
		(fp_line
			(start -0.299974 0.150114)
			(end -0.299974 -0.150114)
			(stroke
				(width 0.1)
				(type default)
			)
			(layer "F.Fab")
		)
		(fp_line
			(start -0.299974 -0.150114)
			(end 0.299974 -0.150114)
			(stroke
				(width 0.1)
				(type default)
			)
			(layer "F.Fab")
		)
		(pad "1" smd rect
			(at -0.2667 0 180)
			(size 0.3048 0.381)
			(layers "F.Cu" "F.Mask" "F.Paste")
			(net "P5E_PEX2_STN2_TX_DP<36>")
		)
		(pad "2" smd rect
			(at 0.2667 0 180)
			(size 0.3048 0.381)
			(layers "F.Cu" "F.Mask" "F.Paste")
			(net "P5E_PEX2_STN2_TX_C_DP<36>")
		)
	)
	(footprint ""
		(layer "F.Cu")
		(at 234.855512 -231.416606 90)
		(property "Reference" "R4522"
			(at 0 0 90)
			(layer "F.SilkS")
			(hide yes)
			(effects
				(font
					(size 1.27 1.27)
				)
			)
		)
		(property "Value" ""
			(at 0 0 90)
			(layer "F.Fab")
			(effects
				(font
					(size 1.27 1.27)
				)
			)
		)
		(duplicate_pad_numbers_are_jumpers no)
		(fp_line
			(start 0.7874 -0.4064)
			(end 0.7874 0.4064)
			(stroke
				(width 0.1524)
				(type default)
			)
			(layer "F.SilkS")
		)
		(fp_line
			(start -0.7874 -0.4064)
			(end 0.7874 -0.4064)
			(stroke
				(width 0.1524)
				(type default)
			)
			(layer "F.SilkS")
		)
		(fp_line
			(start 0.7874 0.4064)
			(end -0.7874 0.4064)
			(stroke
				(width 0.1524)
				(type default)
			)
			(layer "F.SilkS")
		)
		(fp_line
			(start -0.7874 0.4064)
			(end -0.7874 -0.4064)
			(stroke
				(width 0.1524)
				(type default)
			)
			(layer "F.SilkS")
		)
		(fp_line
			(start -0.12065 -0.305054)
			(end -0.12065 -0.2794)
			(stroke
				(width 0.1)
				(type default)
			)
			(layer "F.Fab")
		)
		(fp_line
			(start -0.67945 -0.305054)
			(end -0.12065 -0.305054)
			(stroke
				(width 0.1)
				(type default)
			)
			(layer "F.Fab")
		)
		(fp_line
			(start 0.67945 -0.3048)
			(end 0.67945 0.3048)
			(stroke
				(width 0.1)
				(type default)
			)
			(layer "F.Fab")
		)
		(fp_line
			(start 0.12065 -0.3048)
			(end 0.67945 -0.3048)
			(stroke
				(width 0.1)
				(type default)
			)
			(layer "F.Fab")
		)
		(fp_line
			(start 0.12065 -0.2794)
			(end 0.12065 -0.3048)
			(stroke
				(width 0.1)
				(type default)
			)
			(layer "F.Fab")
		)
		(fp_line
			(start -0.12065 -0.2794)
			(end 0.12065 -0.2794)
			(stroke
				(width 0.1)
				(type default)
			)
			(layer "F.Fab")
		)
		(fp_line
			(start 0.120396 0.2794)
			(end -0.12065 0.2794)
			(stroke
				(width 0.1)
				(type default)
			)
			(layer "F.Fab")
		)
		(fp_line
			(start -0.12065 0.2794)
			(end -0.12065 0.3048)
			(stroke
				(width 0.1)
				(type default)
			)
			(layer "F.Fab")
		)
		(fp_line
			(start 0.67945 0.3048)
			(end 0.120396 0.3048)
			(stroke
				(width 0.1)
				(type default)
			)
			(layer "F.Fab")
		)
		(fp_line
			(start 0.120396 0.3048)
			(end 0.120396 0.2794)
			(stroke
				(width 0.1)
				(type default)
			)
			(layer "F.Fab")
		)
		(fp_line
			(start -0.12065 0.3048)
			(end -0.67945 0.3048)
			(stroke
				(width 0.1)
				(type default)
			)
			(layer "F.Fab")
		)
		(fp_line
			(start -0.67945 0.3048)
			(end -0.67945 -0.305054)
			(stroke
				(width 0.1)
				(type default)
			)
			(layer "F.Fab")
		)
		(pad "1" smd circle
			(at -0.40005 0 90)
			(size 0 0)
			(layers "F.Cu" "F.Mask" "F.Paste")
			(net "SSD8_PWRDIS_BIC")
		)
		(pad "2" smd circle
			(at 0.40005 0 90)
			(size 0 0)
			(layers "F.Cu" "F.Mask" "F.Paste")
			(net "SSD8_PWRDIS_BIC_R")
		)
	)
	(footprint ""
		(layer "F.Cu")
		(at 359.161842 -194.397122 180)
		(property "Reference" "R4617"
			(at 0 0 180)
			(layer "F.SilkS")
			(hide yes)
			(effects
				(font
					(size 1.27 1.27)
				)
			)
		)
		(property "Value" ""
			(at 0 0 180)
			(layer "F.Fab")
			(effects
				(font
					(size 1.27 1.27)
				)
			)
		)
		(duplicate_pad_numbers_are_jumpers no)
		(fp_line
			(start 0.7874 0.4064)
			(end -0.7874 0.4064)
			(stroke
				(width 0.1524)
				(type default)
			)
			(layer "F.SilkS")
		)
		(fp_line
			(start 0.7874 -0.4064)
			(end 0.7874 0.4064)
			(stroke
				(width 0.1524)
				(type default)
			)
			(layer "F.SilkS")
		)
		(fp_line
			(start -0.7874 0.4064)
			(end -0.7874 -0.4064)
			(stroke
				(width 0.1524)
				(type default)
			)
			(layer "F.SilkS")
		)
		(fp_line
			(start -0.7874 -0.4064)
			(end 0.7874 -0.4064)
			(stroke
				(width 0.1524)
				(type default)
			)
			(layer "F.SilkS")
		)
		(fp_line
			(start 0.67945 0.3048)
			(end 0.120396 0.3048)
			(stroke
				(width 0.1)
				(type default)
			)
			(layer "F.Fab")
		)
		(fp_line
			(start 0.67945 -0.3048)
			(end 0.67945 0.3048)
			(stroke
				(width 0.1)
				(type default)
			)
			(layer "F.Fab")
		)
		(fp_line
			(start 0.12065 -0.2794)
			(end 0.12065 -0.3048)
			(stroke
				(width 0.1)
				(type default)
			)
			(layer "F.Fab")
		)
		(fp_line
			(start 0.12065 -0.3048)
			(end 0.67945 -0.3048)
			(stroke
				(width 0.1)
				(type default)
			)
			(layer "F.Fab")
		)
		(fp_line
			(start 0.120396 0.3048)
			(end 0.120396 0.2794)
			(stroke
				(width 0.1)
				(type default)
			)
			(layer "F.Fab")
		)
		(fp_line
			(start 0.120396 0.2794)
			(end -0.12065 0.2794)
			(stroke
				(width 0.1)
				(type default)
			)
			(layer "F.Fab")
		)
		(fp_line
			(start -0.12065 0.3048)
			(end -0.67945 0.3048)
			(stroke
				(width 0.1)
				(type default)
			)
			(layer "F.Fab")
		)
		(fp_line
			(start -0.12065 0.2794)
			(end -0.12065 0.3048)
			(stroke
				(width 0.1)
				(type default)
			)
			(layer "F.Fab")
		)
		(fp_line
			(start -0.12065 -0.2794)
			(end 0.12065 -0.2794)
			(stroke
				(width 0.1)
				(type default)
			)
			(layer "F.Fab")
		)
		(fp_line
			(start -0.12065 -0.305054)
			(end -0.12065 -0.2794)
			(stroke
				(width 0.1)
				(type default)
			)
			(layer "F.Fab")
		)
		(fp_line
			(start -0.67945 0.3048)
			(end -0.67945 -0.305054)
			(stroke
				(width 0.1)
				(type default)
			)
			(layer "F.Fab")
		)
		(fp_line
			(start -0.67945 -0.305054)
			(end -0.12065 -0.305054)
			(stroke
				(width 0.1)
				(type default)
			)
			(layer "F.Fab")
		)
		(pad "1" smd circle
			(at -0.40005 0 180)
			(size 0 0)
			(layers "F.Cu" "F.Mask" "F.Paste")
			(net "PEX0_PCA9555_INT_R_N")
		)
		(pad "2" smd circle
			(at 0.40005 0 180)
			(size 0 0)
			(layers "F.Cu" "F.Mask" "F.Paste")
			(net "PEX0_PCA9555_INT_N")
		)
	)
	(footprint ""
		(layer "F.Cu")
		(at 371.968014 -18.437098)
		(property "Reference" "R1721"
			(at 0 0 0)
			(layer "F.SilkS")
			(hide yes)
			(effects
				(font
					(size 1.27 1.27)
				)
			)
		)
		(property "Value" ""
			(at 0 0 0)
			(layer "F.Fab")
			(effects
				(font
					(size 1.27 1.27)
				)
			)
		)
		(duplicate_pad_numbers_are_jumpers no)
		(fp_line
			(start -0.7874 -0.4064)
			(end 0.7874 -0.4064)
			(stroke
				(width 0.1524)
				(type default)
			)
			(layer "F.SilkS")
		)
		(fp_line
			(start -0.7874 0.4064)
			(end -0.7874 -0.4064)
			(stroke
				(width 0.1524)
				(type default)
			)
			(layer "F.SilkS")
		)
		(fp_line
			(start 0.7874 -0.4064)
			(end 0.7874 0.4064)
			(stroke
				(width 0.1524)
				(type default)
			)
			(layer "F.SilkS")
		)
		(fp_line
			(start 0.7874 0.4064)
			(end -0.7874 0.4064)
			(stroke
				(width 0.1524)
				(type default)
			)
			(layer "F.SilkS")
		)
		(fp_line
			(start -0.67945 -0.305054)
			(end -0.12065 -0.305054)
			(stroke
				(width 0.1)
				(type default)
			)
			(layer "F.Fab")
		)
		(fp_line
			(start -0.67945 0.3048)
			(end -0.67945 -0.305054)
			(stroke
				(width 0.1)
				(type default)
			)
			(layer "F.Fab")
		)
		(fp_line
			(start -0.12065 -0.305054)
			(end -0.12065 -0.2794)
			(stroke
				(width 0.1)
				(type default)
			)
			(layer "F.Fab")
		)
		(fp_line
			(start -0.12065 -0.2794)
			(end 0.12065 -0.2794)
			(stroke
				(width 0.1)
				(type default)
			)
			(layer "F.Fab")
		)
		(fp_line
			(start -0.12065 0.2794)
			(end -0.12065 0.3048)
			(stroke
				(width 0.1)
				(type default)
			)
			(layer "F.Fab")
		)
		(fp_line
			(start -0.12065 0.3048)
			(end -0.67945 0.3048)
			(stroke
				(width 0.1)
				(type default)
			)
			(layer "F.Fab")
		)
		(fp_line
			(start 0.120396 0.2794)
			(end -0.12065 0.2794)
			(stroke
				(width 0.1)
				(type default)
			)
			(layer "F.Fab")
		)
		(fp_line
			(start 0.120396 0.3048)
			(end 0.120396 0.2794)
			(stroke
				(width 0.1)
				(type default)
			)
			(layer "F.Fab")
		)
		(fp_line
			(start 0.12065 -0.3048)
			(end 0.67945 -0.3048)
			(stroke
				(width 0.1)
				(type default)
			)
			(layer "F.Fab")
		)
		(fp_line
			(start 0.12065 -0.2794)
			(end 0.12065 -0.3048)
			(stroke
				(width 0.1)
				(type default)
			)
			(layer "F.Fab")
		)
		(fp_line
			(start 0.67945 -0.3048)
			(end 0.67945 0.3048)
			(stroke
				(width 0.1)
				(type default)
			)
			(layer "F.Fab")
		)
		(fp_line
			(start 0.67945 0.3048)
			(end 0.120396 0.3048)
			(stroke
				(width 0.1)
				(type default)
			)
			(layer "F.Fab")
		)
		(pad "1" smd circle
			(at -0.40005 0)
			(size 0 0)
			(layers "F.Cu" "F.Mask" "F.Paste")
			(net "SMB_ISO_SSD12_R_SCL")
		)
		(pad "2" smd circle
			(at 0.40005 0)
			(size 0 0)
			(layers "F.Cu" "F.Mask" "F.Paste")
			(net "SMB_ISO_SSD12_SCL")
		)
	)
	(footprint ""
		(layer "F.Cu")
		(at 102.483412 -222.064072 -90)
		(property "Reference" "PR188"
			(at 0 0 270)
			(layer "F.SilkS")
			(hide yes)
			(effects
				(font
					(size 1.27 1.27)
				)
			)
		)
		(property "Value" ""
			(at 0 0 270)
			(layer "F.Fab")
			(effects
				(font
					(size 1.27 1.27)
				)
			)
		)
		(duplicate_pad_numbers_are_jumpers no)
		(fp_line
			(start -0.7874 0.4064)
			(end -0.7874 -0.4064)
			(stroke
				(width 0.1524)
				(type default)
			)
			(layer "F.SilkS")
		)
		(fp_line
			(start 0.7874 0.4064)
			(end -0.7874 0.4064)
			(stroke
				(width 0.1524)
				(type default)
			)
			(layer "F.SilkS")
		)
		(fp_line
			(start -0.7874 -0.4064)
			(end 0.7874 -0.4064)
			(stroke
				(width 0.1524)
				(type default)
			)
			(layer "F.SilkS")
		)
		(fp_line
			(start 0.7874 -0.4064)
			(end 0.7874 0.4064)
			(stroke
				(width 0.1524)
				(type default)
			)
			(layer "F.SilkS")
		)
		(fp_line
			(start -0.67945 0.3048)
			(end -0.67945 -0.305054)
			(stroke
				(width 0.1)
				(type default)
			)
			(layer "F.Fab")
		)
		(fp_line
			(start -0.12065 0.3048)
			(end -0.67945 0.3048)
			(stroke
				(width 0.1)
				(type default)
			)
			(layer "F.Fab")
		)
		(fp_line
			(start 0.120396 0.3048)
			(end 0.120396 0.2794)
			(stroke
				(width 0.1)
				(type default)
			)
			(layer "F.Fab")
		)
		(fp_line
			(start 0.67945 0.3048)
			(end 0.120396 0.3048)
			(stroke
				(width 0.1)
				(type default)
			)
			(layer "F.Fab")
		)
		(fp_line
			(start -0.12065 0.2794)
			(end -0.12065 0.3048)
			(stroke
				(width 0.1)
				(type default)
			)
			(layer "F.Fab")
		)
		(fp_line
			(start 0.120396 0.2794)
			(end -0.12065 0.2794)
			(stroke
				(width 0.1)
				(type default)
			)
			(layer "F.Fab")
		)
		(fp_line
			(start -0.12065 -0.2794)
			(end 0.12065 -0.2794)
			(stroke
				(width 0.1)
				(type default)
			)
			(layer "F.Fab")
		)
		(fp_line
			(start 0.12065 -0.2794)
			(end 0.12065 -0.3048)
			(stroke
				(width 0.1)
				(type default)
			)
			(layer "F.Fab")
		)
		(fp_line
			(start 0.12065 -0.3048)
			(end 0.67945 -0.3048)
			(stroke
				(width 0.1)
				(type default)
			)
			(layer "F.Fab")
		)
		(fp_line
			(start 0.67945 -0.3048)
			(end 0.67945 0.3048)
			(stroke
				(width 0.1)
				(type default)
			)
			(layer "F.Fab")
		)
		(fp_line
			(start -0.67945 -0.305054)
			(end -0.12065 -0.305054)
			(stroke
				(width 0.1)
				(type default)
			)
			(layer "F.Fab")
		)
		(fp_line
			(start -0.12065 -0.305054)
			(end -0.12065 -0.2794)
			(stroke
				(width 0.1)
				(type default)
			)
			(layer "F.Fab")
		)
		(pad "1" smd circle
			(at -0.40005 0 270)
			(size 0 0)
			(layers "F.Cu" "F.Mask" "F.Paste")
			(net "GND")
		)
		(pad "2" smd circle
			(at 0.40005 0 270)
			(size 0 0)
			(layers "F.Cu" "F.Mask" "F.Paste")
			(net "P1V8_PEX_FB")
		)
	)
)
